(kicad_pcb
	(version 20241229)
	(generator "pcbnew")
	(generator_version "9.0")
	(general
		(thickness 1.61)
		(legacy_teardrops no)
	)
	(paper "A3")
	(title_block
		(title "RDIMM DDR5 Tester")
		(date "2026-05-21")
		(rev "2.2.0")
		(company "Antmicro")
		(comment 9 "footprints 755-759 of 796")
	)
	(layers
		(0 "F.Cu" signal)
		(4 "In1.Cu" power)
		(6 "In2.Cu" mixed)
		(8 "In3.Cu" power)
		(10 "In4.Cu" mixed)
		(12 "In5.Cu" power)
		(14 "In6.Cu" mixed)
		(16 "In7.Cu" power)
		(18 "In8.Cu" power)
		(20 "In9.Cu" mixed)
		(22 "In10.Cu" power)
		(2 "B.Cu" signal)
		(9 "F.Adhes" user "F.Adhesive")
		(11 "B.Adhes" user "B.Adhesive")
		(13 "F.Paste" user)
		(15 "B.Paste" user)
		(5 "F.SilkS" user "F.Silkscreen")
		(7 "B.SilkS" user "B.Silkscreen")
		(1 "F.Mask" user)
		(3 "B.Mask" user)
		(17 "Dwgs.User" user "User.Drawings")
		(19 "Cmts.User" user "User.Comments")
		(21 "Eco1.User" user "User.Eco1")
		(23 "Eco2.User" user "User.Eco2")
		(25 "Edge.Cuts" user)
		(27 "Margin" user)
		(31 "F.CrtYd" user "F.Courtyard")
		(29 "B.CrtYd" user "B.Courtyard")
		(35 "F.Fab" user)
		(33 "B.Fab" user)
	)
	(footprint "antmicro-footprints:R_0402_1005Metric"
		(layer "B.Cu")
		(at 236.22 156.182 -90)
		(descr "Resistor SMD 0402")
		(tags "resistor SMD 0402")
		(property "Reference" "R209"
			(at 0.918 -0.44 90)
			(layer "B.SilkS")
			(effects
				(font
					(size 0.7 0.7)
					(thickness 0.15)
				)
				(justify left bottom mirror)
			)
		)
		(property "Value" "R_0R_0402"
			(at -1.011843 -1.772047 90)
			(layer "B.Fab")
			(effects
				(font
					(size 0.7 0.7)
					(thickness 0.15)
				)
				(justify left bottom mirror)
			)
		)
		(property "Datasheet" "https://industrial.panasonic.com/cdbs/www-data/pdf/RDA0000/AOA0000C301.pdf"
			(at 0 0 270)
			(layer "F.Fab")
			(hide yes)
			(effects
				(font
					(size 1.27 1.27)
					(thickness 0.15)
				)
			)
		)
		(property "MPN" "ERJ2GE0R00X"
			(at 0 0 270)
			(unlocked yes)
			(layer "B.Fab")
			(hide yes)
			(effects
				(font
					(size 1 1)
					(thickness 0.15)
				)
				(justify mirror)
			)
		)
		(property "Manufacturer" "Panasonic"
			(at 0 0 270)
			(unlocked yes)
			(layer "B.Fab")
			(hide yes)
			(effects
				(font
					(size 1 1)
					(thickness 0.15)
				)
				(justify mirror)
			)
		)
		(property "License" "Apache-2.0"
			(at 0 0 270)
			(unlocked yes)
			(layer "B.Fab")
			(hide yes)
			(effects
				(font
					(size 1 1)
					(thickness 0.15)
				)
				(justify mirror)
			)
		)
		(property "Author" "Antmicro"
			(at 0 0 270)
			(unlocked yes)
			(layer "B.Fab")
			(hide yes)
			(effects
				(font
					(size 1 1)
					(thickness 0.15)
				)
				(justify mirror)
			)
		)
		(property "Val" "0R"
			(at 0 0 270)
			(unlocked yes)
			(layer "B.Fab")
			(hide yes)
			(effects
				(font
					(size 1 1)
					(thickness 0.15)
				)
				(justify mirror)
			)
		)
		(property "Tolerance" "~"
			(at 0 0 270)
			(unlocked yes)
			(layer "B.Fab")
			(hide yes)
			(effects
				(font
					(size 1 1)
					(thickness 0.15)
				)
				(justify mirror)
			)
		)
		(property "Current" "1A"
			(at 0 0 270)
			(unlocked yes)
			(layer "B.Fab")
			(hide yes)
			(effects
				(font
					(size 1 1)
					(thickness 0.15)
				)
				(justify mirror)
			)
		)
		(sheetname "/Supply/DC-DC IO/")
		(sheetfile "dc-dc-io.kicad_sch")
		(attr smd)
		(fp_rect
			(start -0.925 0.47)
			(end 0.925 -0.47)
			(stroke
				(width 0.05)
				(type default)
			)
			(fill no)
			(layer "B.CrtYd")
		)
		(fp_rect
			(start -0.5 0.25)
			(end 0.5 -0.25)
			(stroke
				(width 0.15)
				(type solid)
			)
			(fill no)
			(layer "B.Fab")
		)
		(fp_text user "Author: Antmicro"
			(at -0.95 -4.169 90)
			(layer "B.Fab")
			(effects
				(font
					(size 0.7 0.7)
					(thickness 0.15)
				)
				(justify left bottom mirror)
			)
		)
		(fp_text user "${REFERENCE}"
			(at -0.95 -3.168 90)
			(layer "B.Fab")
			(effects
				(font
					(size 0.7 0.7)
					(thickness 0.15)
				)
				(justify left bottom mirror)
			)
		)
		(fp_text user "License: Apache-2.0"
			(at -0.95 -5.169 90)
			(layer "B.Fab")
			(effects
				(font
					(size 0.7 0.7)
					(thickness 0.15)
				)
				(justify left bottom mirror)
			)
		)
		(pad "1" smd roundrect
			(at -0.48 0 270)
			(size 0.59 0.64)
			(layers "B.Cu" "B.Mask" "B.Paste")
			(roundrect_rratio 0.25)
			(net 730 "Net-(U28-IN1+)")
			(pintype "passive")
		)
		(pad "2" smd roundrect
			(at 0.48 0 270)
			(size 0.59 0.64)
			(layers "B.Cu" "B.Mask" "B.Paste")
			(roundrect_rratio 0.25)
			(net 685 "/Supply/DC-DC IO/3V3_SEN_+")
			(pintype "passive")
		)
	)
	(footprint "antmicro-footprints:TP_SMD_1mm"
		(layer "B.Cu")
		(at 215 180.65 90)
		(property "Reference" "TP10"
			(at 0.7 0.4 90)
			(layer "B.SilkS")
			(effects
				(font
					(size 0.7 0.7)
					(thickness 0.15)
				)
				(justify right bottom mirror)
			)
		)
		(property "Value" "TP_1mm_SMD"
			(at 0 -1.4 90)
			(layer "B.Fab")
			(effects
				(font
					(size 0.7 0.7)
					(thickness 0.15)
				)
				(justify right bottom mirror)
			)
		)
		(property "MPN" ""
			(at 0 0 90)
			(unlocked yes)
			(layer "B.Fab")
			(hide yes)
			(effects
				(font
					(size 1 1)
					(thickness 0.15)
				)
				(justify mirror)
			)
		)
		(property "Manufacturer" ""
			(at 0 0 90)
			(unlocked yes)
			(layer "B.Fab")
			(hide yes)
			(effects
				(font
					(size 1 1)
					(thickness 0.15)
				)
				(justify mirror)
			)
		)
		(property "Author" "Antmicro"
			(at 0 0 90)
			(unlocked yes)
			(layer "B.Fab")
			(hide yes)
			(effects
				(font
					(size 1 1)
					(thickness 0.15)
				)
				(justify mirror)
			)
		)
		(property "License" "Apache-2.0"
			(at 0 0 90)
			(unlocked yes)
			(layer "B.Fab")
			(hide yes)
			(effects
				(font
					(size 1 1)
					(thickness 0.15)
				)
				(justify mirror)
			)
		)
		(sheetname "/Supply/DC-DC VCCINT/")
		(sheetfile "dc-dc-vccint.kicad_sch")
		(attr exclude_from_pos_files)
		(fp_circle
			(center 0 0)
			(end 0.6 0)
			(stroke
				(width 0.05)
				(type default)
			)
			(fill no)
			(layer "B.CrtYd")
		)
		(fp_text user "License: Apache-2.0"
			(at -0.5 -5.2 270)
			(layer "B.Fab")
			(effects
				(font
					(size 0.7 0.7)
					(thickness 0.15)
				)
				(justify left bottom mirror)
			)
		)
		(fp_text user "${REFERENCE}"
			(at -0.5 -2.8 270)
			(layer "B.Fab")
			(effects
				(font
					(size 0.7 0.7)
					(thickness 0.15)
				)
				(justify left bottom mirror)
			)
		)
		(fp_text user "Author: Antmicro"
			(at -0.5 -4 270)
			(layer "B.Fab")
			(effects
				(font
					(size 0.7 0.7)
					(thickness 0.15)
				)
				(justify left bottom mirror)
			)
		)
		(pad "1" smd circle
			(at 0 0 90)
			(size 1 1)
			(layers "B.Cu" "B.Mask")
			(net 741 "/Supply/DC-DC VCCINT/PWR.~{ALT}1")
			(pinfunction "1")
			(pintype "passive")
		)
	)
	(footprint "antmicro-footprints:C_0402_1005Metric_EIA"
		(layer "B.Cu")
		(at 194.5 158)
		(descr "Capacitor SMD 0402 (1005 Metric), square (rectangular) end terminal, IPC_7351 nominal, (Body size source: IPC-SM-782 page 76, https://www.pcb-3d.com/wordpress/wp-content/uploads/ipc-sm-782a_amendment_1_and_2.pdf)")
		(tags "capacitor 0402")
		(property "Reference" "C18"
			(at -32.15 -10.3 0)
			(layer "B.SilkS")
			(effects
				(font
					(size 0.7 0.7)
					(thickness 0.15)
				)
				(justify right bottom mirror)
			)
		)
		(property "Value" "C_10u_10V_0402"
			(at 0 -1.169 0)
			(layer "B.Fab")
			(effects
				(font
					(size 0.7 0.7)
					(thickness 0.15)
				)
				(justify right bottom mirror)
			)
		)
		(property "Datasheet" "https://www.murata.com/products/productdetail?partno=GRM155R61A106ME11%23"
			(at 0 0 0)
			(layer "F.Fab")
			(hide yes)
			(effects
				(font
					(size 1.27 1.27)
					(thickness 0.15)
				)
			)
		)
		(property "MPN" "GRM155R61A106ME11D"
			(at 0 0 0)
			(unlocked yes)
			(layer "B.Fab")
			(hide yes)
			(effects
				(font
					(size 1 1)
					(thickness 0.15)
				)
				(justify mirror)
			)
		)
		(property "Manufacturer" "Murata"
			(at 0 0 0)
			(unlocked yes)
			(layer "B.Fab")
			(hide yes)
			(effects
				(font
					(size 1 1)
					(thickness 0.15)
				)
				(justify mirror)
			)
		)
		(property "License" "Apache-2.0"
			(at 0 0 0)
			(unlocked yes)
			(layer "B.Fab")
			(hide yes)
			(effects
				(font
					(size 1 1)
					(thickness 0.15)
				)
				(justify mirror)
			)
		)
		(property "Author" "Antmicro"
			(at 0 0 0)
			(unlocked yes)
			(layer "B.Fab")
			(hide yes)
			(effects
				(font
					(size 1 1)
					(thickness 0.15)
				)
				(justify mirror)
			)
		)
		(property "Val" "10u"
			(at 0 0 0)
			(unlocked yes)
			(layer "B.Fab")
			(hide yes)
			(effects
				(font
					(size 1 1)
					(thickness 0.15)
				)
				(justify mirror)
			)
		)
		(property "Voltage" "10V"
			(at 0 0 0)
			(unlocked yes)
			(layer "B.Fab")
			(hide yes)
			(effects
				(font
					(size 1 1)
					(thickness 0.15)
				)
				(justify mirror)
			)
		)
		(property "Dielectric" "X5R"
			(at 0 0 0)
			(unlocked yes)
			(layer "B.Fab")
			(hide yes)
			(effects
				(font
					(size 1 1)
					(thickness 0.15)
				)
				(justify mirror)
			)
		)
		(sheetname "/FPGA power/")
		(sheetfile "fpga-power.kicad_sch")
		(attr smd)
		(fp_rect
			(start -0.95 0.45)
			(end 0.95 -0.45)
			(stroke
				(width 0.05)
				(type default)
			)
			(fill no)
			(layer "B.CrtYd")
		)
		(fp_line
			(start -0.5 -0.248)
			(end -0.5 0.25)
			(stroke
				(width 0.15)
				(type solid)
			)
			(layer "B.Fab")
		)
		(fp_line
			(start -0.5 0.25)
			(end 0.498 0.25)
			(stroke
				(width 0.15)
				(type solid)
			)
			(layer "B.Fab")
		)
		(fp_line
			(start 0.498 -0.248)
			(end -0.5 -0.248)
			(stroke
				(width 0.15)
				(type solid)
			)
			(layer "B.Fab")
		)
		(fp_line
			(start 0.498 0.25)
			(end 0.498 -0.248)
			(stroke
				(width 0.15)
				(type solid)
			)
			(layer "B.Fab")
		)
		(fp_text user "License: Apache-2.0"
			(at -0.9656 -4.369 180)
			(layer "B.Fab")
			(effects
				(font
					(size 0.7 0.7)
					(thickness 0.15)
				)
				(justify left bottom mirror)
			)
		)
		(fp_text user "Author: Antmicro"
			(at -0.9656 -5.569 180)
			(layer "B.Fab")
			(effects
				(font
					(size 0.7 0.7)
					(thickness 0.15)
				)
				(justify left bottom mirror)
			)
		)
		(fp_text user "${REFERENCE}"
			(at -0.9656 -3.169 180)
			(layer "B.Fab")
			(effects
				(font
					(size 0.7 0.7)
					(thickness 0.15)
				)
				(justify left bottom mirror)
			)
		)
		(pad "1" smd roundrect
			(at -0.5 0 270)
			(size 0.6 0.6)
			(layers "B.Cu" "B.Mask" "B.Paste")
			(roundrect_rratio 0.25)
			(net 1 "GND")
			(pintype "passive")
		)
		(pad "2" smd roundrect
			(at 0.498 0)
			(size 0.6 0.6)
			(layers "B.Cu" "B.Mask" "B.Paste")
			(roundrect_rratio 0.25)
			(net 797 "+1V8")
			(pintype "passive")
		)
	)
	(footprint "antmicro-footprints:R_0402_1005Metric"
		(layer "B.Cu")
		(at 168.1 154.5)
		(descr "Resistor SMD 0402")
		(tags "resistor SMD 0402")
		(property "Reference" "R1"
			(at 0.9 0.4 0)
			(layer "B.SilkS")
			(effects
				(font
					(size 0.7 0.7)
					(thickness 0.15)
				)
				(justify right bottom mirror)
			)
		)
		(property "Value" "R_10k_0402"
			(at -1.011843 -1.772047 0)
			(layer "B.Fab")
			(effects
				(font
					(size 0.7 0.7)
					(thickness 0.15)
				)
				(justify right bottom mirror)
			)
		)
		(property "Datasheet" "https://www.bourns.com/docs/product-datasheets/cr.pdf"
			(at 0 0 0)
			(layer "F.Fab")
			(hide yes)
			(effects
				(font
					(size 1.27 1.27)
					(thickness 0.15)
				)
			)
		)
		(property "Manufacturer" "Bourns"
			(at 0 0 0)
			(unlocked yes)
			(layer "B.Fab")
			(hide yes)
			(effects
				(font
					(size 1 1)
					(thickness 0.15)
				)
				(justify mirror)
			)
		)
		(property "MPN" "CR0402-FX-1002GLF"
			(at 0 0 0)
			(unlocked yes)
			(layer "B.Fab")
			(hide yes)
			(effects
				(font
					(size 1 1)
					(thickness 0.15)
				)
				(justify mirror)
			)
		)
		(property "Val" "10k"
			(at 0 0 0)
			(unlocked yes)
			(layer "B.Fab")
			(hide yes)
			(effects
				(font
					(size 1 1)
					(thickness 0.15)
				)
				(justify mirror)
			)
		)
		(property "License" "Apache-2.0"
			(at 0 0 0)
			(unlocked yes)
			(layer "B.Fab")
			(hide yes)
			(effects
				(font
					(size 1 1)
					(thickness 0.15)
				)
				(justify mirror)
			)
		)
		(property "Author" "Antmicro"
			(at 0 0 0)
			(unlocked yes)
			(layer "B.Fab")
			(hide yes)
			(effects
				(font
					(size 1 1)
					(thickness 0.15)
				)
				(justify mirror)
			)
		)
		(property "Tolerance" "1%"
			(at 0 0 0)
			(unlocked yes)
			(layer "B.Fab")
			(hide yes)
			(effects
				(font
					(size 1 1)
					(thickness 0.15)
				)
				(justify mirror)
			)
		)
		(sheetname "/HyperRAM + QSPI Flash/")
		(sheetfile "hyperram-flash.kicad_sch")
		(attr smd)
		(fp_rect
			(start -0.925 0.47)
			(end 0.925 -0.47)
			(stroke
				(width 0.05)
				(type default)
			)
			(fill no)
			(layer "B.CrtYd")
		)
		(fp_rect
			(start -0.5 0.25)
			(end 0.5 -0.25)
			(stroke
				(width 0.15)
				(type solid)
			)
			(fill no)
			(layer "B.Fab")
		)
		(fp_text user "${REFERENCE}"
			(at -0.95 -3.168 180)
			(layer "B.Fab")
			(effects
				(font
					(size 0.7 0.7)
					(thickness 0.15)
				)
				(justify left bottom mirror)
			)
		)
		(fp_text user "License: Apache-2.0"
			(at -0.95 -5.169 180)
			(layer "B.Fab")
			(effects
				(font
					(size 0.7 0.7)
					(thickness 0.15)
				)
				(justify left bottom mirror)
			)
		)
		(fp_text user "Author: Antmicro"
			(at -0.95 -4.169 180)
			(layer "B.Fab")
			(effects
				(font
					(size 0.7 0.7)
					(thickness 0.15)
				)
				(justify left bottom mirror)
			)
		)
		(pad "1" smd roundrect
			(at -0.48 0)
			(size 0.59 0.64)
			(layers "B.Cu" "B.Mask" "B.Paste")
			(roundrect_rratio 0.25)
			(net 797 "+1V8")
			(pintype "passive")
		)
		(pad "2" smd roundrect
			(at 0.48 0)
			(size 0.59 0.64)
			(layers "B.Cu" "B.Mask" "B.Paste")
			(roundrect_rratio 0.25)
			(net 623 "/FPGA banks HP/HyperRAM.~{RESET}")
			(pintype "passive")
		)
	)
	(footprint "antmicro-footprints:R_0402_1005Metric"
		(layer "B.Cu")
		(at 222.875 177.915 90)
		(descr "Resistor SMD 0402")
		(tags "resistor SMD 0402")
		(property "Reference" "R203"
			(at -1.11 1.75 90)
			(layer "B.SilkS")
			(effects
				(font
					(size 0.7 0.7)
					(thickness 0.15)
				)
				(justify right bottom mirror)
			)
		)
		(property "Value" "R_0R_0402"
			(at 0.215 1.675 90)
			(layer "B.Fab")
			(effects
				(font
					(size 0.7 0.7)
					(thickness 0.15)
				)
				(justify right bottom mirror)
			)
		)
		(property "Datasheet" "https://industrial.panasonic.com/cdbs/www-data/pdf/RDA0000/AOA0000C301.pdf"
			(at 0 0 90)
			(layer "F.Fab")
			(hide yes)
			(effects
				(font
					(size 1.27 1.27)
					(thickness 0.15)
				)
			)
		)
		(property "MPN" "ERJ2GE0R00X"
			(at 0 0 90)
			(unlocked yes)
			(layer "B.Fab")
			(hide yes)
			(effects
				(font
					(size 1 1)
					(thickness 0.15)
				)
				(justify mirror)
			)
		)
		(property "Manufacturer" "Panasonic"
			(at 0 0 90)
			(unlocked yes)
			(layer "B.Fab")
			(hide yes)
			(effects
				(font
					(size 1 1)
					(thickness 0.15)
				)
				(justify mirror)
			)
		)
		(property "License" "Apache-2.0"
			(at 0 0 90)
			(unlocked yes)
			(layer "B.Fab")
			(hide yes)
			(effects
				(font
					(size 1 1)
					(thickness 0.15)
				)
				(justify mirror)
			)
		)
		(property "Author" "Antmicro"
			(at 0 0 90)
			(unlocked yes)
			(layer "B.Fab")
			(hide yes)
			(effects
				(font
					(size 1 1)
					(thickness 0.15)
				)
				(justify mirror)
			)
		)
		(property "Val" "0R"
			(at 0 0 90)
			(unlocked yes)
			(layer "B.Fab")
			(hide yes)
			(effects
				(font
					(size 1 1)
					(thickness 0.15)
				)
				(justify mirror)
			)
		)
		(property "Tolerance" "~"
			(at 0 0 90)
			(unlocked yes)
			(layer "B.Fab")
			(hide yes)
			(effects
				(font
					(size 1 1)
					(thickness 0.15)
				)
				(justify mirror)
			)
		)
		(property "Current" "1A"
			(at 0 0 90)
			(unlocked yes)
			(layer "B.Fab")
			(hide yes)
			(effects
				(font
					(size 1 1)
					(thickness 0.15)
				)
				(justify mirror)
			)
		)
		(sheetname "/Supply/DC-DC VCCINT/")
		(sheetfile "dc-dc-vccint.kicad_sch")
		(attr smd exclude_from_bom dnp)
		(fp_rect
			(start -0.925 0.47)
			(end 0.925 -0.47)
			(stroke
				(width 0.05)
				(type default)
			)
			(fill no)
			(layer "B.CrtYd")
		)
		(fp_rect
			(start -0.5 0.25)
			(end 0.5 -0.25)
			(stroke
				(width 0.15)
				(type solid)
			)
			(fill no)
			(layer "B.Fab")
		)
		(fp_text user "${REFERENCE}"
			(at -0.95 -3.168 270)
			(layer "B.Fab")
			(effects
				(font
					(size 0.7 0.7)
					(thickness 0.15)
				)
				(justify left bottom mirror)
			)
		)
		(fp_text user "License: Apache-2.0"
			(at -0.95 -5.169 270)
			(layer "B.Fab")
			(effects
				(font
					(size 0.7 0.7)
					(thickness 0.15)
				)
				(justify left bottom mirror)
			)
		)
		(fp_text user "Author: Antmicro"
			(at -0.95 -4.169 270)
			(layer "B.Fab")
			(effects
				(font
					(size 0.7 0.7)
					(thickness 0.15)
				)
				(justify left bottom mirror)
			)
		)
		(pad "1" smd roundrect
			(at -0.48 0 90)
			(size 0.59 0.64)
			(layers "B.Cu" "B.Mask" "B.Paste")
			(roundrect_rratio 0.25)
			(net 756 "Net-(C264-Pad2)")
			(pintype "passive")
		)
		(pad "2" smd roundrect
			(at 0.48 0 90)
			(size 0.59 0.64)
			(layers "B.Cu" "B.Mask" "B.Paste")
			(roundrect_rratio 0.25)
			(net 223 "/Supply/DC-DC VCCINT/0V85_REG0")
			(pintype "passive")
		)
	)
)
